(kicad_pcb
	(version 20241229)
	(generator "pcbnew")
	(generator_version "9.0")
	(general
		(thickness 1.599998)
		(legacy_teardrops no)
	)
	(paper "A4")
	(title_block
		(date "2023-02-12")
		(rev "1.1.5")
		(comment 9 "footprints 141-146 of 473")
	)
	(layers
		(0 "F.Cu" signal)
		(4 "In1.Cu" power "In1.GND")
		(6 "In2.Cu" signal)
		(8 "In3.Cu" power "In3.GND")
		(10 "In4.Cu" power "In4.VCC")
		(12 "In5.Cu" signal)
		(14 "In6.Cu" power "In6.VCC")
		(2 "B.Cu" signal)
		(9 "F.Adhes" user "F.Adhesive")
		(11 "B.Adhes" user "B.Adhesive")
		(13 "F.Paste" user)
		(15 "B.Paste" user)
		(5 "F.SilkS" user "F.Silkscreen")
		(7 "B.SilkS" user "B.Silkscreen")
		(1 "F.Mask" user)
		(3 "B.Mask" user)
		(17 "Dwgs.User" user "User.Drawings")
		(19 "Cmts.User" user "User.Comments")
		(21 "Eco1.User" user "User.Eco1")
		(23 "Eco2.User" user "User.Eco2")
		(25 "Edge.Cuts" user)
		(27 "Margin" user)
		(31 "F.CrtYd" user "F.Courtyard")
		(29 "B.CrtYd" user "B.Courtyard")
		(35 "F.Fab" user)
		(33 "B.Fab" user)
	)
	(footprint "antmicro-footprints:R_0402_1005Metric"
		(layer "F.Cu")
		(at 198.736328 71.697157 -90)
		(descr "Resistor SMD 0402")
		(tags "resistor SMD 0402")
		(property "Reference" "R27"
			(at 1.102843 -1.263672 270)
			(layer "F.SilkS")
			(effects
				(font
					(size 0.7 0.7)
					(thickness 0.15)
				)
				(justify left bottom)
			)
		)
		(property "Value" "R_330R_0402"
			(at 0 1.4 270)
			(layer "F.Fab")
			(effects
				(font
					(size 0.7 0.7)
					(thickness 0.15)
				)
				(justify left bottom)
			)
		)
		(property "Description" "330R resistor in 0402 package with 1% tolerance"
			(at 0 0 270)
			(layer "F.Fab")
			(hide yes)
			(effects
				(font
					(size 1.27 1.27)
					(thickness 0.15)
				)
			)
		)
		(property "Author" "Antmicro"
			(at 127.039171 270.433485 0)
			(layer "F.Fab")
			(hide yes)
			(effects
				(font
					(size 1 1)
					(thickness 0.15)
				)
			)
		)
		(property "License" "Apache-2.0"
			(at 127.039171 270.433485 0)
			(layer "F.Fab")
			(hide yes)
			(effects
				(font
					(size 1 1)
					(thickness 0.15)
				)
			)
		)
		(property "MPN" "CR0402-FX-3300GLF"
			(at 127.039171 270.433485 0)
			(layer "F.Fab")
			(hide yes)
			(effects
				(font
					(size 1 1)
					(thickness 0.15)
				)
			)
		)
		(property "Manufacturer" "Bourns"
			(at 127.039171 270.433485 0)
			(layer "F.Fab")
			(hide yes)
			(effects
				(font
					(size 1 1)
					(thickness 0.15)
				)
			)
		)
		(property "Tolerance" "1%"
			(at 127.039171 270.433485 0)
			(layer "F.Fab")
			(hide yes)
			(effects
				(font
					(size 1 1)
					(thickness 0.15)
				)
			)
		)
		(property "Val" "330R"
			(at 127.039171 270.433485 0)
			(layer "F.Fab")
			(hide yes)
			(effects
				(font
					(size 1 1)
					(thickness 0.15)
				)
			)
		)
		(sheetname "Interfaces")
		(sheetfile "interfaces.kicad_sch")
		(attr smd)
		(fp_rect
			(start -0.93 -0.47)
			(end 0.93 0.47)
			(stroke
				(width 0.05)
				(type solid)
			)
			(fill no)
			(layer "F.CrtYd")
		)
		(fp_rect
			(start -0.5 -0.25)
			(end 0.5 0.25)
			(stroke
				(width 0.15)
				(type solid)
			)
			(fill no)
			(layer "F.Fab")
		)
		(pad "1" smd roundrect
			(at -0.485 0 270)
			(size 0.59 0.64)
			(layers "F.Cu" "F.Mask" "F.Paste")
			(roundrect_rratio 0.25)
			(net 72 "Net-(D2-Pad2)")
			(pintype "passive")
		)
		(pad "2" smd roundrect
			(at 0.485 0 270)
			(size 0.59 0.64)
			(layers "F.Cu" "F.Mask" "F.Paste")
			(roundrect_rratio 0.25)
			(net 211 "Net-(Q2-D)")
			(pintype "passive")
		)
	)
	(footprint "antmicro-footprints:R_0402_1005Metric"
		(layer "F.Cu")
		(at 194.736328 71.697157 -90)
		(descr "Resistor SMD 0402")
		(tags "resistor SMD 0402")
		(property "Reference" "R28"
			(at 1.102843 -1.263672 270)
			(layer "F.SilkS")
			(effects
				(font
					(size 0.7 0.7)
					(thickness 0.15)
				)
				(justify left bottom)
			)
		)
		(property "Value" "R_330R_0402"
			(at 0 1.4 270)
			(layer "F.Fab")
			(effects
				(font
					(size 0.7 0.7)
					(thickness 0.15)
				)
				(justify left bottom)
			)
		)
		(property "Description" "330R resistor in 0402 package with 1% tolerance"
			(at 0 0 270)
			(layer "F.Fab")
			(hide yes)
			(effects
				(font
					(size 1.27 1.27)
					(thickness 0.15)
				)
			)
		)
		(property "Author" "Antmicro"
			(at 123.039171 266.433485 0)
			(layer "F.Fab")
			(hide yes)
			(effects
				(font
					(size 1 1)
					(thickness 0.15)
				)
			)
		)
		(property "License" "Apache-2.0"
			(at 123.039171 266.433485 0)
			(layer "F.Fab")
			(hide yes)
			(effects
				(font
					(size 1 1)
					(thickness 0.15)
				)
			)
		)
		(property "MPN" "CR0402-FX-3300GLF"
			(at 123.039171 266.433485 0)
			(layer "F.Fab")
			(hide yes)
			(effects
				(font
					(size 1 1)
					(thickness 0.15)
				)
			)
		)
		(property "Manufacturer" "Bourns"
			(at 123.039171 266.433485 0)
			(layer "F.Fab")
			(hide yes)
			(effects
				(font
					(size 1 1)
					(thickness 0.15)
				)
			)
		)
		(property "Tolerance" "1%"
			(at 123.039171 266.433485 0)
			(layer "F.Fab")
			(hide yes)
			(effects
				(font
					(size 1 1)
					(thickness 0.15)
				)
			)
		)
		(property "Val" "330R"
			(at 123.039171 266.433485 0)
			(layer "F.Fab")
			(hide yes)
			(effects
				(font
					(size 1 1)
					(thickness 0.15)
				)
			)
		)
		(sheetname "Interfaces")
		(sheetfile "interfaces.kicad_sch")
		(attr smd)
		(fp_rect
			(start -0.93 -0.47)
			(end 0.93 0.47)
			(stroke
				(width 0.05)
				(type solid)
			)
			(fill no)
			(layer "F.CrtYd")
		)
		(fp_rect
			(start -0.5 -0.25)
			(end 0.5 0.25)
			(stroke
				(width 0.15)
				(type solid)
			)
			(fill no)
			(layer "F.Fab")
		)
		(pad "1" smd roundrect
			(at -0.485 0 270)
			(size 0.59 0.64)
			(layers "F.Cu" "F.Mask" "F.Paste")
			(roundrect_rratio 0.25)
			(net 73 "Net-(D3-Pad2)")
			(pintype "passive")
		)
		(pad "2" smd roundrect
			(at 0.485 0 270)
			(size 0.59 0.64)
			(layers "F.Cu" "F.Mask" "F.Paste")
			(roundrect_rratio 0.25)
			(net 228 "Net-(Q3-D)")
			(pintype "passive")
		)
	)
	(footprint "antmicro-footprints:R_0402_1005Metric"
		(layer "F.Cu")
		(at 202.736328 71.697157 -90)
		(descr "Resistor SMD 0402")
		(tags "resistor SMD 0402")
		(property "Reference" "R29"
			(at 1.102843 -1.263672 270)
			(layer "F.SilkS")
			(effects
				(font
					(size 0.7 0.7)
					(thickness 0.15)
				)
				(justify left bottom)
			)
		)
		(property "Value" "R_330R_0402"
			(at 0 1.4 270)
			(layer "F.Fab")
			(effects
				(font
					(size 0.7 0.7)
					(thickness 0.15)
				)
				(justify left bottom)
			)
		)
		(property "Description" "330R resistor in 0402 package with 1% tolerance"
			(at 0 0 270)
			(layer "F.Fab")
			(hide yes)
			(effects
				(font
					(size 1.27 1.27)
					(thickness 0.15)
				)
			)
		)
		(property "Author" "Antmicro"
			(at 131.039171 274.433485 0)
			(layer "F.Fab")
			(hide yes)
			(effects
				(font
					(size 1 1)
					(thickness 0.15)
				)
			)
		)
		(property "License" "Apache-2.0"
			(at 131.039171 274.433485 0)
			(layer "F.Fab")
			(hide yes)
			(effects
				(font
					(size 1 1)
					(thickness 0.15)
				)
			)
		)
		(property "MPN" "CR0402-FX-3300GLF"
			(at 131.039171 274.433485 0)
			(layer "F.Fab")
			(hide yes)
			(effects
				(font
					(size 1 1)
					(thickness 0.15)
				)
			)
		)
		(property "Manufacturer" "Bourns"
			(at 131.039171 274.433485 0)
			(layer "F.Fab")
			(hide yes)
			(effects
				(font
					(size 1 1)
					(thickness 0.15)
				)
			)
		)
		(property "Tolerance" "1%"
			(at 131.039171 274.433485 0)
			(layer "F.Fab")
			(hide yes)
			(effects
				(font
					(size 1 1)
					(thickness 0.15)
				)
			)
		)
		(property "Val" "330R"
			(at 131.039171 274.433485 0)
			(layer "F.Fab")
			(hide yes)
			(effects
				(font
					(size 1 1)
					(thickness 0.15)
				)
			)
		)
		(sheetname "Interfaces")
		(sheetfile "interfaces.kicad_sch")
		(attr smd)
		(fp_rect
			(start -0.93 -0.47)
			(end 0.93 0.47)
			(stroke
				(width 0.05)
				(type solid)
			)
			(fill no)
			(layer "F.CrtYd")
		)
		(fp_rect
			(start -0.5 -0.25)
			(end 0.5 0.25)
			(stroke
				(width 0.15)
				(type solid)
			)
			(fill no)
			(layer "F.Fab")
		)
		(pad "1" smd roundrect
			(at -0.485 0 270)
			(size 0.59 0.64)
			(layers "F.Cu" "F.Mask" "F.Paste")
			(roundrect_rratio 0.25)
			(net 52 "Net-(D5-Pad2)")
			(pintype "passive")
		)
		(pad "2" smd roundrect
			(at 0.485 0 270)
			(size 0.59 0.64)
			(layers "F.Cu" "F.Mask" "F.Paste")
			(roundrect_rratio 0.25)
			(net 230 "Net-(Q4-D)")
			(pintype "passive")
		)
	)
	(footprint "antmicro-footprints:R_0402_1005Metric"
		(layer "F.Cu")
		(at 206.736328 71.697157 -90)
		(descr "Resistor SMD 0402")
		(tags "resistor SMD 0402")
		(property "Reference" "R30"
			(at 1.102843 -1.263672 270)
			(layer "F.SilkS")
			(effects
				(font
					(size 0.7 0.7)
					(thickness 0.15)
				)
				(justify left bottom)
			)
		)
		(property "Value" "R_330R_0402"
			(at 0 1.4 270)
			(layer "F.Fab")
			(effects
				(font
					(size 0.7 0.7)
					(thickness 0.15)
				)
				(justify left bottom)
			)
		)
		(property "Description" "330R resistor in 0402 package with 1% tolerance"
			(at 0 0 270)
			(layer "F.Fab")
			(hide yes)
			(effects
				(font
					(size 1.27 1.27)
					(thickness 0.15)
				)
			)
		)
		(property "Author" "Antmicro"
			(at 135.039171 278.433485 0)
			(layer "F.Fab")
			(hide yes)
			(effects
				(font
					(size 1 1)
					(thickness 0.15)
				)
			)
		)
		(property "License" "Apache-2.0"
			(at 135.039171 278.433485 0)
			(layer "F.Fab")
			(hide yes)
			(effects
				(font
					(size 1 1)
					(thickness 0.15)
				)
			)
		)
		(property "MPN" "CR0402-FX-3300GLF"
			(at 135.039171 278.433485 0)
			(layer "F.Fab")
			(hide yes)
			(effects
				(font
					(size 1 1)
					(thickness 0.15)
				)
			)
		)
		(property "Manufacturer" "Bourns"
			(at 135.039171 278.433485 0)
			(layer "F.Fab")
			(hide yes)
			(effects
				(font
					(size 1 1)
					(thickness 0.15)
				)
			)
		)
		(property "Tolerance" "1%"
			(at 135.039171 278.433485 0)
			(layer "F.Fab")
			(hide yes)
			(effects
				(font
					(size 1 1)
					(thickness 0.15)
				)
			)
		)
		(property "Val" "330R"
			(at 135.039171 278.433485 0)
			(layer "F.Fab")
			(hide yes)
			(effects
				(font
					(size 1 1)
					(thickness 0.15)
				)
			)
		)
		(sheetname "Interfaces")
		(sheetfile "interfaces.kicad_sch")
		(attr smd)
		(fp_rect
			(start -0.93 -0.47)
			(end 0.93 0.47)
			(stroke
				(width 0.05)
				(type solid)
			)
			(fill no)
			(layer "F.CrtYd")
		)
		(fp_rect
			(start -0.5 -0.25)
			(end 0.5 0.25)
			(stroke
				(width 0.15)
				(type solid)
			)
			(fill no)
			(layer "F.Fab")
		)
		(pad "1" smd roundrect
			(at -0.485 0 270)
			(size 0.59 0.64)
			(layers "F.Cu" "F.Mask" "F.Paste")
			(roundrect_rratio 0.25)
			(net 53 "Net-(D6-Pad2)")
			(pintype "passive")
		)
		(pad "2" smd roundrect
			(at 0.485 0 270)
			(size 0.59 0.64)
			(layers "F.Cu" "F.Mask" "F.Paste")
			(roundrect_rratio 0.25)
			(net 231 "Net-(Q5-D)")
			(pintype "passive")
		)
	)
	(footprint "antmicro-footprints:SC70-3"
		(layer "F.Cu")
		(at 190.736328 74.697157 90)
		(property "Reference" "Q1"
			(at -0.602843 -1.336328 90)
			(layer "F.SilkS")
			(effects
				(font
					(size 0.7 0.7)
					(thickness 0.15)
				)
				(justify left bottom)
			)
		)
		(property "Value" "BSS138PW"
			(at 0 2.3 90)
			(layer "F.Fab")
			(effects
				(font
					(size 0.7 0.7)
					(thickness 0.15)
				)
				(justify left bottom)
			)
		)
		(property "Description" "60 V, 320 mA N-channel enhancement mode Trench MOSFET, SC-70-3 aka SOT-323 package"
			(at 0 0 90)
			(layer "F.Fab")
			(hide yes)
			(effects
				(font
					(size 1.27 1.27)
					(thickness 0.15)
				)
			)
		)
		(property "Author" "Antmicro"
			(at 265.433485 -116.039171 0)
			(layer "F.Fab")
			(hide yes)
			(effects
				(font
					(size 1 1)
					(thickness 0.15)
				)
			)
		)
		(property "License" "Apache-2.0"
			(at 265.433485 -116.039171 0)
			(layer "F.Fab")
			(hide yes)
			(effects
				(font
					(size 1 1)
					(thickness 0.15)
				)
			)
		)
		(property "MPN" "BSS138PW"
			(at 265.433485 -116.039171 0)
			(layer "F.Fab")
			(hide yes)
			(effects
				(font
					(size 1 1)
					(thickness 0.15)
				)
			)
		)
		(property "Manufacturer" "Nexperia"
			(at 265.433485 -116.039171 0)
			(layer "F.Fab")
			(hide yes)
			(effects
				(font
					(size 1 1)
					(thickness 0.15)
				)
			)
		)
		(sheetname "Interfaces")
		(sheetfile "interfaces.kicad_sch")
		(attr smd)
		(fp_line
			(start -0.3 -1)
			(end 0.627 -0.999)
			(stroke
				(width 0.15)
				(type solid)
			)
			(layer "F.SilkS")
		)
		(fp_line
			(start 0.627 -0.6)
			(end 0.627 -0.999)
			(stroke
				(width 0.15)
				(type solid)
			)
			(layer "F.SilkS")
		)
		(fp_line
			(start 0.627 0.6)
			(end 0.627 1.001)
			(stroke
				(width 0.15)
				(type solid)
			)
			(layer "F.SilkS")
		)
		(fp_line
			(start -0.3 1)
			(end 0.627 1.001)
			(stroke
				(width 0.15)
				(type solid)
			)
			(layer "F.SilkS")
		)
		(fp_line
			(start 0.9 -1.3)
			(end 0.9 -0.4)
			(stroke
				(width 0.05)
				(type solid)
			)
			(layer "F.CrtYd")
		)
		(fp_line
			(start -0.9 -1.3)
			(end 0.9 -1.3)
			(stroke
				(width 0.05)
				(type solid)
			)
			(layer "F.CrtYd")
		)
		(fp_line
			(start -0.9 -1.3)
			(end -0.9 -1)
			(stroke
				(width 0.05)
				(type solid)
			)
			(layer "F.CrtYd")
		)
		(fp_line
			(start -0.9 -1)
			(end -1.4 -1)
			(stroke
				(width 0.05)
				(type solid)
			)
			(layer "F.CrtYd")
		)
		(fp_line
			(start 1.4 -0.4)
			(end 1.4 0.4)
			(stroke
				(width 0.05)
				(type solid)
			)
			(layer "F.CrtYd")
		)
		(fp_line
			(start 0.9 -0.4)
			(end 1.4 -0.4)
			(stroke
				(width 0.05)
				(type solid)
			)
			(layer "F.CrtYd")
		)
		(fp_line
			(start 1.4 0.4)
			(end 0.9 0.4)
			(stroke
				(width 0.05)
				(type solid)
			)
			(layer "F.CrtYd")
		)
		(fp_line
			(start 0.9 0.4)
			(end 0.9 1.3)
			(stroke
				(width 0.05)
				(type solid)
			)
			(layer "F.CrtYd")
		)
		(fp_line
			(start -0.9 1)
			(end -1.4 1)
			(stroke
				(width 0.05)
				(type solid)
			)
			(layer "F.CrtYd")
		)
		(fp_line
			(start -1.4 1)
			(end -1.4 -1)
			(stroke
				(width 0.05)
				(type solid)
			)
			(layer "F.CrtYd")
		)
		(fp_line
			(start 0.9 1.3)
			(end -0.9 1.3)
			(stroke
				(width 0.05)
				(type solid)
			)
			(layer "F.CrtYd")
		)
		(fp_line
			(start -0.9 1.3)
			(end -0.9 1)
			(stroke
				(width 0.05)
				(type solid)
			)
			(layer "F.CrtYd")
		)
		(fp_rect
			(start -0.623 -0.999)
			(end 0.627 1.001)
			(stroke
				(width 0.15)
				(type solid)
			)
			(fill no)
			(layer "F.Fab")
		)
		(pad "1" smd rect
			(at -0.95 -0.65 180)
			(size 0.6 0.8)
			(layers "F.Cu" "F.Mask" "F.Paste")
			(net 56 "USR_LED1")
			(pinfunction "G")
			(pintype "bidirectional")
		)
		(pad "2" smd rect
			(at -0.95 0.65 180)
			(size 0.6 0.8)
			(layers "F.Cu" "F.Mask" "F.Paste")
			(net 5 "GND")
			(pinfunction "S")
			(pintype "bidirectional")
		)
		(pad "3" smd rect
			(at 0.95 0 180)
			(size 0.6 0.8)
			(layers "F.Cu" "F.Mask" "F.Paste")
			(net 209 "Net-(Q1-D)")
			(pinfunction "D")
			(pintype "bidirectional")
		)
	)
	(footprint "antmicro-footprints:SC70-3"
		(layer "F.Cu")
		(at 198.736328 74.697157 90)
		(property "Reference" "Q2"
			(at -0.602843 -1.336328 90)
			(layer "F.SilkS")
			(effects
				(font
					(size 0.7 0.7)
					(thickness 0.15)
				)
				(justify left bottom)
			)
		)
		(property "Value" "BSS138PW"
			(at 0 2.3 90)
			(layer "F.Fab")
			(effects
				(font
					(size 0.7 0.7)
					(thickness 0.15)
				)
				(justify left bottom)
			)
		)
		(property "Description" "60 V, 320 mA N-channel enhancement mode Trench MOSFET, SC-70-3 aka SOT-323 package"
			(at 0 0 90)
			(layer "F.Fab")
			(hide yes)
			(effects
				(font
					(size 1.27 1.27)
					(thickness 0.15)
				)
			)
		)
		(property "Author" "Antmicro"
			(at 273.433485 -124.039171 0)
			(layer "F.Fab")
			(hide yes)
			(effects
				(font
					(size 1 1)
					(thickness 0.15)
				)
			)
		)
		(property "License" "Apache-2.0"
			(at 273.433485 -124.039171 0)
			(layer "F.Fab")
			(hide yes)
			(effects
				(font
					(size 1 1)
					(thickness 0.15)
				)
			)
		)
		(property "MPN" "BSS138PW"
			(at 273.433485 -124.039171 0)
			(layer "F.Fab")
			(hide yes)
			(effects
				(font
					(size 1 1)
					(thickness 0.15)
				)
			)
		)
		(property "Manufacturer" "Nexperia"
			(at 273.433485 -124.039171 0)
			(layer "F.Fab")
			(hide yes)
			(effects
				(font
					(size 1 1)
					(thickness 0.15)
				)
			)
		)
		(sheetname "Interfaces")
		(sheetfile "interfaces.kicad_sch")
		(attr smd)
		(fp_line
			(start -0.3 -1)
			(end 0.627 -0.999)
			(stroke
				(width 0.15)
				(type solid)
			)
			(layer "F.SilkS")
		)
		(fp_line
			(start 0.627 -0.6)
			(end 0.627 -0.999)
			(stroke
				(width 0.15)
				(type solid)
			)
			(layer "F.SilkS")
		)
		(fp_line
			(start 0.627 0.6)
			(end 0.627 1.001)
			(stroke
				(width 0.15)
				(type solid)
			)
			(layer "F.SilkS")
		)
		(fp_line
			(start -0.3 1)
			(end 0.627 1.001)
			(stroke
				(width 0.15)
				(type solid)
			)
			(layer "F.SilkS")
		)
		(fp_line
			(start 0.9 -1.3)
			(end 0.9 -0.4)
			(stroke
				(width 0.05)
				(type solid)
			)
			(layer "F.CrtYd")
		)
		(fp_line
			(start -0.9 -1.3)
			(end 0.9 -1.3)
			(stroke
				(width 0.05)
				(type solid)
			)
			(layer "F.CrtYd")
		)
		(fp_line
			(start -0.9 -1.3)
			(end -0.9 -1)
			(stroke
				(width 0.05)
				(type solid)
			)
			(layer "F.CrtYd")
		)
		(fp_line
			(start -0.9 -1)
			(end -1.4 -1)
			(stroke
				(width 0.05)
				(type solid)
			)
			(layer "F.CrtYd")
		)
		(fp_line
			(start 1.4 -0.4)
			(end 1.4 0.4)
			(stroke
				(width 0.05)
				(type solid)
			)
			(layer "F.CrtYd")
		)
		(fp_line
			(start 0.9 -0.4)
			(end 1.4 -0.4)
			(stroke
				(width 0.05)
				(type solid)
			)
			(layer "F.CrtYd")
		)
		(fp_line
			(start 1.4 0.4)
			(end 0.9 0.4)
			(stroke
				(width 0.05)
				(type solid)
			)
			(layer "F.CrtYd")
		)
		(fp_line
			(start 0.9 0.4)
			(end 0.9 1.3)
			(stroke
				(width 0.05)
				(type solid)
			)
			(layer "F.CrtYd")
		)
		(fp_line
			(start -0.9 1)
			(end -1.4 1)
			(stroke
				(width 0.05)
				(type solid)
			)
			(layer "F.CrtYd")
		)
		(fp_line
			(start -1.4 1)
			(end -1.4 -1)
			(stroke
				(width 0.05)
				(type solid)
			)
			(layer "F.CrtYd")
		)
		(fp_line
			(start 0.9 1.3)
			(end -0.9 1.3)
			(stroke
				(width 0.05)
				(type solid)
			)
			(layer "F.CrtYd")
		)
		(fp_line
			(start -0.9 1.3)
			(end -0.9 1)
			(stroke
				(width 0.05)
				(type solid)
			)
			(layer "F.CrtYd")
		)
		(fp_rect
			(start -0.623 -0.999)
			(end 0.627 1.001)
			(stroke
				(width 0.15)
				(type solid)
			)
			(fill no)
			(layer "F.Fab")
		)
		(pad "1" smd rect
			(at -0.95 -0.65 180)
			(size 0.6 0.8)
			(layers "F.Cu" "F.Mask" "F.Paste")
			(net 57 "USR_LED3")
			(pinfunction "G")
			(pintype "bidirectional")
		)
		(pad "2" smd rect
			(at -0.95 0.65 180)
			(size 0.6 0.8)
			(layers "F.Cu" "F.Mask" "F.Paste")
			(net 5 "GND")
			(pinfunction "S")
			(pintype "bidirectional")
		)
		(pad "3" smd rect
			(at 0.95 0 180)
			(size 0.6 0.8)
			(layers "F.Cu" "F.Mask" "F.Paste")
			(net 211 "Net-(Q2-D)")
			(pinfunction "D")
			(pintype "bidirectional")
		)
	)
)
